(kicad_pcb
	(version 20260206)
	(generator "pcbnew")
	(generator_version "10.0")
	(general
		(thickness 1.6)
		(legacy_teardrops no)
	)
	(paper "A4")
	(title_block
		(title "12092022_DA0F0TMDCD0_F0T_Management_Board_D_brd_V3_OCP.brd")
		(comment 1 "Grand Teton / footprints 1326-1331 of 1440")
	)
	(layers
		(0 "F.Cu" signal "TOP")
		(4 "In1.Cu" signal "GND")
		(6 "In2.Cu" signal "IN1")
		(8 "In3.Cu" signal "GND1")
		(10 "In4.Cu" signal "IN2")
		(12 "In5.Cu" signal "VCC")
		(14 "In6.Cu" signal "VCC1")
		(16 "In7.Cu" signal "IN3")
		(18 "In8.Cu" signal "GND2")
		(20 "In9.Cu" signal "IN4")
		(22 "In10.Cu" signal "GND3")
		(2 "B.Cu" signal "BOTTOM")
		(9 "F.Adhes" user "F.Adhesive")
		(11 "B.Adhes" user "B.Adhesive")
		(13 "F.Paste" user "Package Geometry/Pastemask Top")
		(15 "B.Paste" user "Package Geometry/Pastemask Bottom")
		(5 "F.SilkS" user "Ref Des/Silkscreen Top")
		(7 "B.SilkS" user "Ref Des/Silkscreen Bottom")
		(1 "F.Mask" user "Board Geometry/Soldermask Top")
		(3 "B.Mask" user "Board Geometry/Soldermask Bottom")
		(17 "Dwgs.User" user "User.Drawings")
		(19 "Cmts.User" user "User.Comments")
		(21 "Eco1.User" user "User.Eco1")
		(23 "Eco2.User" user "User.Eco2")
		(25 "Edge.Cuts" user "Board Geometry/Outline")
		(27 "Margin" user)
		(31 "F.CrtYd" user "Package Geometry/Place Bound Top")
		(29 "B.CrtYd" user "Package Geometry/Place Bound Bottom")
		(35 "F.Fab" user "Ref Des/Assembly Top")
		(33 "B.Fab" user "Ref Des/Assembly Bottom")
	)
	(footprint ""
		(layer "B.Cu")
		(at 72.029066 -60.839096 -90)
		(property "Reference" "C78"
			(at 0 0 90)
			(layer "B.SilkS")
			(hide yes)
			(effects
				(font
					(size 1.27 1.27)
				)
				(justify mirror)
			)
		)
		(property "Value" ""
			(at 0 0 90)
			(layer "B.Fab")
			(effects
				(font
					(size 1.27 1.27)
				)
				(justify mirror)
			)
		)
		(duplicate_pad_numbers_are_jumpers no)
		(fp_line
			(start -0.7874 0.4064)
			(end 0.7874 0.4064)
			(stroke
				(width 0.1524)
				(type default)
			)
			(layer "B.SilkS")
		)
		(fp_line
			(start 0.7874 0.4064)
			(end 0.7874 -0.4064)
			(stroke
				(width 0.1524)
				(type default)
			)
			(layer "B.SilkS")
		)
		(fp_line
			(start -0.7874 -0.4064)
			(end -0.7874 0.4064)
			(stroke
				(width 0.1524)
				(type default)
			)
			(layer "B.SilkS")
		)
		(fp_line
			(start 0.7874 -0.4064)
			(end -0.7874 -0.4064)
			(stroke
				(width 0.1524)
				(type default)
			)
			(layer "B.SilkS")
		)
		(fp_line
			(start -0.67945 0.3048)
			(end -0.120396 0.3048)
			(stroke
				(width 0.1)
				(type default)
			)
			(layer "B.Fab")
		)
		(fp_line
			(start -0.120396 0.3048)
			(end -0.120396 0.2794)
			(stroke
				(width 0.1)
				(type default)
			)
			(layer "B.Fab")
		)
		(fp_line
			(start 0.12065 0.3048)
			(end 0.67945 0.3048)
			(stroke
				(width 0.1)
				(type default)
			)
			(layer "B.Fab")
		)
		(fp_line
			(start 0.67945 0.3048)
			(end 0.67945 -0.305054)
			(stroke
				(width 0.1)
				(type default)
			)
			(layer "B.Fab")
		)
		(fp_line
			(start -0.120396 0.2794)
			(end 0.12065 0.2794)
			(stroke
				(width 0.1)
				(type default)
			)
			(layer "B.Fab")
		)
		(fp_line
			(start 0.12065 0.2794)
			(end 0.12065 0.3048)
			(stroke
				(width 0.1)
				(type default)
			)
			(layer "B.Fab")
		)
		(fp_line
			(start -0.12065 -0.2794)
			(end -0.12065 -0.3048)
			(stroke
				(width 0.1)
				(type default)
			)
			(layer "B.Fab")
		)
		(fp_line
			(start 0.12065 -0.2794)
			(end -0.12065 -0.2794)
			(stroke
				(width 0.1)
				(type default)
			)
			(layer "B.Fab")
		)
		(fp_line
			(start -0.67945 -0.3048)
			(end -0.67945 0.3048)
			(stroke
				(width 0.1)
				(type default)
			)
			(layer "B.Fab")
		)
		(fp_line
			(start -0.12065 -0.3048)
			(end -0.67945 -0.3048)
			(stroke
				(width 0.1)
				(type default)
			)
			(layer "B.Fab")
		)
		(fp_line
			(start 0.12065 -0.305054)
			(end 0.12065 -0.2794)
			(stroke
				(width 0.1)
				(type default)
			)
			(layer "B.Fab")
		)
		(fp_line
			(start 0.67945 -0.305054)
			(end 0.12065 -0.305054)
			(stroke
				(width 0.1)
				(type default)
			)
			(layer "B.Fab")
		)
		(pad "1" smd circle
			(at 0.40005 0 90)
			(size 0 0)
			(layers "B.Cu" "B.Mask" "B.Paste")
			(net "P1V0_STBY_PE_VCC10A")
		)
		(pad "2" smd circle
			(at -0.40005 0 90)
			(size 0 0)
			(layers "B.Cu" "B.Mask" "B.Paste")
			(net "GND")
		)
	)
	(footprint ""
		(layer "B.Cu")
		(at 85.29955 -47.488094)
		(property "Reference" "C13"
			(at 0 0 0)
			(layer "B.SilkS")
			(hide yes)
			(effects
				(font
					(size 1.27 1.27)
				)
				(justify mirror)
			)
		)
		(property "Value" ""
			(at 0 0 0)
			(layer "B.Fab")
			(effects
				(font
					(size 1.27 1.27)
				)
				(justify mirror)
			)
		)
		(duplicate_pad_numbers_are_jumpers no)
		(fp_line
			(start -0.7874 -0.4064)
			(end -0.7874 0.4064)
			(stroke
				(width 0.1524)
				(type default)
			)
			(layer "B.SilkS")
		)
		(fp_line
			(start -0.7874 0.4064)
			(end 0.7874 0.4064)
			(stroke
				(width 0.1524)
				(type default)
			)
			(layer "B.SilkS")
		)
		(fp_line
			(start 0.7874 -0.4064)
			(end -0.7874 -0.4064)
			(stroke
				(width 0.1524)
				(type default)
			)
			(layer "B.SilkS")
		)
		(fp_line
			(start 0.7874 0.4064)
			(end 0.7874 -0.4064)
			(stroke
				(width 0.1524)
				(type default)
			)
			(layer "B.SilkS")
		)
		(fp_line
			(start -0.67945 -0.3048)
			(end -0.67945 0.3048)
			(stroke
				(width 0.1)
				(type default)
			)
			(layer "B.Fab")
		)
		(fp_line
			(start -0.67945 0.3048)
			(end -0.120396 0.3048)
			(stroke
				(width 0.1)
				(type default)
			)
			(layer "B.Fab")
		)
		(fp_line
			(start -0.12065 -0.3048)
			(end -0.67945 -0.3048)
			(stroke
				(width 0.1)
				(type default)
			)
			(layer "B.Fab")
		)
		(fp_line
			(start -0.12065 -0.2794)
			(end -0.12065 -0.3048)
			(stroke
				(width 0.1)
				(type default)
			)
			(layer "B.Fab")
		)
		(fp_line
			(start -0.120396 0.2794)
			(end 0.12065 0.2794)
			(stroke
				(width 0.1)
				(type default)
			)
			(layer "B.Fab")
		)
		(fp_line
			(start -0.120396 0.3048)
			(end -0.120396 0.2794)
			(stroke
				(width 0.1)
				(type default)
			)
			(layer "B.Fab")
		)
		(fp_line
			(start 0.12065 -0.305054)
			(end 0.12065 -0.2794)
			(stroke
				(width 0.1)
				(type default)
			)
			(layer "B.Fab")
		)
		(fp_line
			(start 0.12065 -0.2794)
			(end -0.12065 -0.2794)
			(stroke
				(width 0.1)
				(type default)
			)
			(layer "B.Fab")
		)
		(fp_line
			(start 0.12065 0.2794)
			(end 0.12065 0.3048)
			(stroke
				(width 0.1)
				(type default)
			)
			(layer "B.Fab")
		)
		(fp_line
			(start 0.12065 0.3048)
			(end 0.67945 0.3048)
			(stroke
				(width 0.1)
				(type default)
			)
			(layer "B.Fab")
		)
		(fp_line
			(start 0.67945 -0.305054)
			(end 0.12065 -0.305054)
			(stroke
				(width 0.1)
				(type default)
			)
			(layer "B.Fab")
		)
		(fp_line
			(start 0.67945 0.3048)
			(end 0.67945 -0.305054)
			(stroke
				(width 0.1)
				(type default)
			)
			(layer "B.Fab")
		)
		(pad "1" smd circle
			(at 0.40005 0 180)
			(size 0 0)
			(layers "B.Cu" "B.Mask" "B.Paste")
			(net "P1V2_AUX")
		)
		(pad "2" smd circle
			(at -0.40005 0 180)
			(size 0 0)
			(layers "B.Cu" "B.Mask" "B.Paste")
			(net "GND")
		)
	)
	(footprint ""
		(layer "B.Cu")
		(at 49.5046 -52.3748 180)
		(property "Reference" "C140"
			(at 0 0 0)
			(layer "B.SilkS")
			(hide yes)
			(effects
				(font
					(size 1.27 1.27)
				)
				(justify mirror)
			)
		)
		(property "Value" ""
			(at 0 0 0)
			(layer "B.Fab")
			(effects
				(font
					(size 1.27 1.27)
				)
				(justify mirror)
			)
		)
		(duplicate_pad_numbers_are_jumpers no)
		(fp_line
			(start 0.7874 0.4064)
			(end 0.7874 -0.4064)
			(stroke
				(width 0.1524)
				(type default)
			)
			(layer "B.SilkS")
		)
		(fp_line
			(start 0.7874 -0.4064)
			(end -0.7874 -0.4064)
			(stroke
				(width 0.1524)
				(type default)
			)
			(layer "B.SilkS")
		)
		(fp_line
			(start -0.7874 0.4064)
			(end 0.7874 0.4064)
			(stroke
				(width 0.1524)
				(type default)
			)
			(layer "B.SilkS")
		)
		(fp_line
			(start -0.7874 -0.4064)
			(end -0.7874 0.4064)
			(stroke
				(width 0.1524)
				(type default)
			)
			(layer "B.SilkS")
		)
		(fp_line
			(start 0.67945 0.3048)
			(end 0.67945 -0.305054)
			(stroke
				(width 0.1)
				(type default)
			)
			(layer "B.Fab")
		)
		(fp_line
			(start 0.67945 -0.305054)
			(end 0.12065 -0.305054)
			(stroke
				(width 0.1)
				(type default)
			)
			(layer "B.Fab")
		)
		(fp_line
			(start 0.12065 0.3048)
			(end 0.67945 0.3048)
			(stroke
				(width 0.1)
				(type default)
			)
			(layer "B.Fab")
		)
		(fp_line
			(start 0.12065 0.2794)
			(end 0.12065 0.3048)
			(stroke
				(width 0.1)
				(type default)
			)
			(layer "B.Fab")
		)
		(fp_line
			(start 0.12065 -0.2794)
			(end -0.12065 -0.2794)
			(stroke
				(width 0.1)
				(type default)
			)
			(layer "B.Fab")
		)
		(fp_line
			(start 0.12065 -0.305054)
			(end 0.12065 -0.2794)
			(stroke
				(width 0.1)
				(type default)
			)
			(layer "B.Fab")
		)
		(fp_line
			(start -0.120396 0.3048)
			(end -0.120396 0.2794)
			(stroke
				(width 0.1)
				(type default)
			)
			(layer "B.Fab")
		)
		(fp_line
			(start -0.120396 0.2794)
			(end 0.12065 0.2794)
			(stroke
				(width 0.1)
				(type default)
			)
			(layer "B.Fab")
		)
		(fp_line
			(start -0.12065 -0.2794)
			(end -0.12065 -0.3048)
			(stroke
				(width 0.1)
				(type default)
			)
			(layer "B.Fab")
		)
		(fp_line
			(start -0.12065 -0.3048)
			(end -0.67945 -0.3048)
			(stroke
				(width 0.1)
				(type default)
			)
			(layer "B.Fab")
		)
		(fp_line
			(start -0.67945 0.3048)
			(end -0.120396 0.3048)
			(stroke
				(width 0.1)
				(type default)
			)
			(layer "B.Fab")
		)
		(fp_line
			(start -0.67945 -0.3048)
			(end -0.67945 0.3048)
			(stroke
				(width 0.1)
				(type default)
			)
			(layer "B.Fab")
		)
		(pad "1" smd circle
			(at 0.40005 0)
			(size 0 0)
			(layers "B.Cu" "B.Mask" "B.Paste")
			(net "P1V2_P1V0_I3C_VDDL2")
		)
		(pad "2" smd circle
			(at -0.40005 0)
			(size 0 0)
			(layers "B.Cu" "B.Mask" "B.Paste")
			(net "GND")
		)
	)
	(footprint ""
		(layer "B.Cu")
		(at 33.655 -70.358)
		(property "Reference" "C231"
			(at 0 0 0)
			(layer "B.SilkS")
			(hide yes)
			(effects
				(font
					(size 1.27 1.27)
				)
				(justify mirror)
			)
		)
		(property "Value" ""
			(at 0 0 0)
			(layer "B.Fab")
			(effects
				(font
					(size 1.27 1.27)
				)
				(justify mirror)
			)
		)
		(duplicate_pad_numbers_are_jumpers no)
		(fp_line
			(start -0.7874 -0.4064)
			(end -0.7874 0.4064)
			(stroke
				(width 0.1524)
				(type default)
			)
			(layer "B.SilkS")
		)
		(fp_line
			(start -0.7874 0.4064)
			(end 0.7874 0.4064)
			(stroke
				(width 0.1524)
				(type default)
			)
			(layer "B.SilkS")
		)
		(fp_line
			(start 0.7874 -0.4064)
			(end -0.7874 -0.4064)
			(stroke
				(width 0.1524)
				(type default)
			)
			(layer "B.SilkS")
		)
		(fp_line
			(start 0.7874 0.4064)
			(end 0.7874 -0.4064)
			(stroke
				(width 0.1524)
				(type default)
			)
			(layer "B.SilkS")
		)
		(fp_line
			(start -0.67945 -0.3048)
			(end -0.67945 0.3048)
			(stroke
				(width 0.1)
				(type default)
			)
			(layer "B.Fab")
		)
		(fp_line
			(start -0.67945 0.3048)
			(end -0.120396 0.3048)
			(stroke
				(width 0.1)
				(type default)
			)
			(layer "B.Fab")
		)
		(fp_line
			(start -0.12065 -0.3048)
			(end -0.67945 -0.3048)
			(stroke
				(width 0.1)
				(type default)
			)
			(layer "B.Fab")
		)
		(fp_line
			(start -0.12065 -0.2794)
			(end -0.12065 -0.3048)
			(stroke
				(width 0.1)
				(type default)
			)
			(layer "B.Fab")
		)
		(fp_line
			(start -0.120396 0.2794)
			(end 0.12065 0.2794)
			(stroke
				(width 0.1)
				(type default)
			)
			(layer "B.Fab")
		)
		(fp_line
			(start -0.120396 0.3048)
			(end -0.120396 0.2794)
			(stroke
				(width 0.1)
				(type default)
			)
			(layer "B.Fab")
		)
		(fp_line
			(start 0.12065 -0.305054)
			(end 0.12065 -0.2794)
			(stroke
				(width 0.1)
				(type default)
			)
			(layer "B.Fab")
		)
		(fp_line
			(start 0.12065 -0.2794)
			(end -0.12065 -0.2794)
			(stroke
				(width 0.1)
				(type default)
			)
			(layer "B.Fab")
		)
		(fp_line
			(start 0.12065 0.2794)
			(end 0.12065 0.3048)
			(stroke
				(width 0.1)
				(type default)
			)
			(layer "B.Fab")
		)
		(fp_line
			(start 0.12065 0.3048)
			(end 0.67945 0.3048)
			(stroke
				(width 0.1)
				(type default)
			)
			(layer "B.Fab")
		)
		(fp_line
			(start 0.67945 -0.305054)
			(end 0.12065 -0.305054)
			(stroke
				(width 0.1)
				(type default)
			)
			(layer "B.Fab")
		)
		(fp_line
			(start 0.67945 0.3048)
			(end 0.67945 -0.305054)
			(stroke
				(width 0.1)
				(type default)
			)
			(layer "B.Fab")
		)
		(pad "1" smd circle
			(at 0.40005 0 180)
			(size 0 0)
			(layers "B.Cu" "B.Mask" "B.Paste")
			(net "P3V3_AUX")
		)
		(pad "2" smd circle
			(at -0.40005 0 180)
			(size 0 0)
			(layers "B.Cu" "B.Mask" "B.Paste")
			(net "GND")
		)
	)
	(footprint ""
		(layer "B.Cu")
		(at 66.1035 -94.8182 90)
		(property "Reference" "Q5"
			(at 2.29743 -1.7907 0)
			(unlocked yes)
			(layer "B.SilkS")
			(effects
				(font
					(size 0.7874 0.5842)
					(thickness 0.1524)
				)
				(justify left mirror)
			)
		)
		(property "Value" ""
			(at 0 0 90)
			(layer "B.Fab")
			(effects
				(font
					(size 1.27 1.27)
				)
				(justify mirror)
			)
		)
		(duplicate_pad_numbers_are_jumpers no)
		(fp_line
			(start 1.834896 -1.550162)
			(end 1.834896 1.550162)
			(stroke
				(width 0.1524)
				(type default)
			)
			(layer "B.SilkS")
		)
		(fp_line
			(start 0.494538 -1.550162)
			(end 1.834896 -1.550162)
			(stroke
				(width 0.1524)
				(type default)
			)
			(layer "B.SilkS")
		)
		(fp_line
			(start -0.494538 -1.550162)
			(end 0 -0.94996)
			(stroke
				(width 0.1524)
				(type default)
			)
			(layer "B.SilkS")
		)
		(fp_line
			(start -1.834896 -1.550162)
			(end -0.494538 -1.550162)
			(stroke
				(width 0.1524)
				(type default)
			)
			(layer "B.SilkS")
		)
		(fp_line
			(start 0 -0.94996)
			(end 0.494538 -1.550162)
			(stroke
				(width 0.1524)
				(type default)
			)
			(layer "B.SilkS")
		)
		(fp_line
			(start 1.834896 1.550162)
			(end -1.834896 1.550162)
			(stroke
				(width 0.1524)
				(type default)
			)
			(layer "B.SilkS")
		)
		(fp_line
			(start -1.834896 1.550162)
			(end -1.834896 -1.550162)
			(stroke
				(width 0.1524)
				(type default)
			)
			(layer "B.SilkS")
		)
		(fp_poly
			(pts
				(xy 1.1938 -1.7145) (xy 0.6858 -2.7305) (xy 1.7018 -2.7305)
			)
			(stroke
				(width 0)
				(type default)
			)
			(fill yes)
			(layer "B.SilkS")
		)
		(fp_line
			(start 0.850138 -1.550162)
			(end -0.850138 -1.550162)
			(stroke
				(width 0.1)
				(type default)
			)
			(layer "B.Fab")
		)
		(fp_line
			(start -0.850138 -1.550162)
			(end -0.850138 1.550162)
			(stroke
				(width 0.1)
				(type default)
			)
			(layer "B.Fab")
		)
		(fp_line
			(start 0.850138 1.550162)
			(end 0.850138 -1.550162)
			(stroke
				(width 0.1)
				(type default)
			)
			(layer "B.Fab")
		)
		(fp_line
			(start -0.850138 1.550162)
			(end 0.850138 1.550162)
			(stroke
				(width 0.1)
				(type default)
			)
			(layer "B.Fab")
		)
		(fp_poly
			(pts
				(xy 2.081784 -0.94996) (xy 3.097784 -1.45796) (xy 3.097784 -0.44196)
			)
			(stroke
				(width 0)
				(type default)
			)
			(fill yes)
			(layer "B.Fab")
		)
		(pad "1" smd rect
			(at 1.199896 -0.94996 180)
			(size 0.7112 1.016)
			(layers "B.Cu" "B.Mask" "B.Paste")
			(net "PGPPA_BMC_AUX_L")
		)
		(pad "2" smd rect
			(at 1.199896 0 180)
			(size 0.7112 1.016)
			(layers "B.Cu" "B.Mask" "B.Paste")
			(net "PGPPA_BMC_AUX_L")
		)
		(pad "3" smd rect
			(at 1.199896 0.94996 180)
			(size 0.7112 1.016)
			(layers "B.Cu" "B.Mask" "B.Paste")
			(net "LPC_ESPI_SEL_N")
		)
		(pad "4" smd rect
			(at -1.199896 0.94996 180)
			(size 0.7112 1.016)
			(layers "B.Cu" "B.Mask" "B.Paste")
			(net "P1V8_AUX")
		)
		(pad "5" smd rect
			(at -1.199896 0 180)
			(size 0.7112 1.016)
			(layers "B.Cu" "B.Mask" "B.Paste")
			(net "PGPPA_BMC_AUX_L")
		)
		(pad "6" smd rect
			(at -1.199896 -0.94996 180)
			(size 0.7112 1.016)
			(layers "B.Cu" "B.Mask" "B.Paste")
			(net "PGPPA_BMC_AUX_L")
		)
	)
	(footprint ""
		(layer "B.Cu")
		(at 12.319 -98.552)
		(property "Reference" "R320"
			(at 0 0 0)
			(layer "B.SilkS")
			(hide yes)
			(effects
				(font
					(size 1.27 1.27)
				)
				(justify mirror)
			)
		)
		(property "Value" ""
			(at 0 0 0)
			(layer "B.Fab")
			(effects
				(font
					(size 1.27 1.27)
				)
				(justify mirror)
			)
		)
		(duplicate_pad_numbers_are_jumpers no)
		(fp_line
			(start -0.7874 -0.4064)
			(end -0.7874 0.4064)
			(stroke
				(width 0.1524)
				(type default)
			)
			(layer "B.SilkS")
		)
		(fp_line
			(start -0.7874 0.4064)
			(end 0.7874 0.4064)
			(stroke
				(width 0.1524)
				(type default)
			)
			(layer "B.SilkS")
		)
		(fp_line
			(start 0.7874 -0.4064)
			(end -0.7874 -0.4064)
			(stroke
				(width 0.1524)
				(type default)
			)
			(layer "B.SilkS")
		)
		(fp_line
			(start 0.7874 0.4064)
			(end 0.7874 -0.4064)
			(stroke
				(width 0.1524)
				(type default)
			)
			(layer "B.SilkS")
		)
		(fp_line
			(start -0.67945 -0.3048)
			(end -0.67945 0.3048)
			(stroke
				(width 0.1)
				(type default)
			)
			(layer "B.Fab")
		)
		(fp_line
			(start -0.67945 0.3048)
			(end -0.120396 0.3048)
			(stroke
				(width 0.1)
				(type default)
			)
			(layer "B.Fab")
		)
		(fp_line
			(start -0.12065 -0.3048)
			(end -0.67945 -0.3048)
			(stroke
				(width 0.1)
				(type default)
			)
			(layer "B.Fab")
		)
		(fp_line
			(start -0.12065 -0.2794)
			(end -0.12065 -0.3048)
			(stroke
				(width 0.1)
				(type default)
			)
			(layer "B.Fab")
		)
		(fp_line
			(start -0.120396 0.2794)
			(end 0.12065 0.2794)
			(stroke
				(width 0.1)
				(type default)
			)
			(layer "B.Fab")
		)
		(fp_line
			(start -0.120396 0.3048)
			(end -0.120396 0.2794)
			(stroke
				(width 0.1)
				(type default)
			)
			(layer "B.Fab")
		)
		(fp_line
			(start 0.12065 -0.305054)
			(end 0.12065 -0.2794)
			(stroke
				(width 0.1)
				(type default)
			)
			(layer "B.Fab")
		)
		(fp_line
			(start 0.12065 -0.2794)
			(end -0.12065 -0.2794)
			(stroke
				(width 0.1)
				(type default)
			)
			(layer "B.Fab")
		)
		(fp_line
			(start 0.12065 0.2794)
			(end 0.12065 0.3048)
			(stroke
				(width 0.1)
				(type default)
			)
			(layer "B.Fab")
		)
		(fp_line
			(start 0.12065 0.3048)
			(end 0.67945 0.3048)
			(stroke
				(width 0.1)
				(type default)
			)
			(layer "B.Fab")
		)
		(fp_line
			(start 0.67945 -0.305054)
			(end 0.12065 -0.305054)
			(stroke
				(width 0.1)
				(type default)
			)
			(layer "B.Fab")
		)
		(fp_line
			(start 0.67945 0.3048)
			(end 0.67945 -0.305054)
			(stroke
				(width 0.1)
				(type default)
			)
			(layer "B.Fab")
		)
		(pad "1" smd circle
			(at 0.40005 0 180)
			(size 0 0)
			(layers "B.Cu" "B.Mask" "B.Paste")
			(net "PWRGD_P2V5_AUX_R1")
		)
		(pad "2" smd circle
			(at -0.40005 0 180)
			(size 0 0)
			(layers "B.Cu" "B.Mask" "B.Paste")
			(net "PWRGD_P2V5_AUX")
		)
	)
)
